(kicad_pcb
	(version 20260206)
	(generator "pcbnew")
	(generator_version "10.0")
	(general
		(thickness 1.6)
		(legacy_teardrops no)
	)
	(paper "A4")
	(title_block
		(title "Bryce Canyon_IOM_M2_16342-2_OCP.brd")
		(comment 1 "Bryce Canyon / footprints 644-650 of 1146")
	)
	(layers
		(0 "F.Cu" signal "TOP")
		(4 "In1.Cu" signal "L2GND")
		(6 "In2.Cu" signal "L3")
		(8 "In3.Cu" signal "L4VCC")
		(10 "In4.Cu" signal "L5VCC")
		(12 "In5.Cu" signal "L6")
		(14 "In6.Cu" signal "L7GND")
		(2 "B.Cu" signal "BOTTOM")
		(9 "F.Adhes" user "F.Adhesive")
		(11 "B.Adhes" user "B.Adhesive")
		(13 "F.Paste" user "Package Geometry/Pastemask Top")
		(15 "B.Paste" user "Package Geometry/Pastemask Bottom")
		(5 "F.SilkS" user "Ref Des/Silkscreen Top")
		(7 "B.SilkS" user "Ref Des/Silkscreen Bottom")
		(1 "F.Mask" user "Board Geometry/Soldermask Top")
		(3 "B.Mask" user "Board Geometry/Soldermask Bottom")
		(17 "Dwgs.User" user "User.Drawings")
		(19 "Cmts.User" user "User.Comments")
		(21 "Eco1.User" user "User.Eco1")
		(23 "Eco2.User" user "User.Eco2")
		(25 "Edge.Cuts" user "Board Geometry/Outline")
		(27 "Margin" user)
		(31 "F.CrtYd" user "Package Geometry/Place Bound Top")
		(29 "B.CrtYd" user "Package Geometry/Place Bound Bottom")
		(35 "F.Fab" user "Ref Des/Assembly Top")
		(33 "B.Fab" user "Ref Des/Assembly Bottom")
	)
	(footprint ""
		(layer "F.Cu")
		(at 60.849002 -136.942068 -90)
		(property "Reference" "R354"
			(at 0 0 270)
			(layer "F.SilkS")
			(hide yes)
			(effects
				(font
					(size 1.27 1.27)
				)
			)
		)
		(property "Value" "4K7R2F-GP"
			(at 0.064008 -3.993896 270)
			(unlocked yes)
			(layer "F.Fab")
			(hide yes)
			(effects
				(font
					(size 1.016 1.016)
					(thickness 0.1524)
				)
			)
		)
		(property "Device Type" "R402H16"
			(at 0.064008 -5.517896 270)
			(unlocked yes)
			(layer "F.Fab")
			(hide yes)
			(effects
				(font
					(size 1.016 1.016)
					(thickness 0.1524)
				)
			)
		)
		(duplicate_pad_numbers_are_jumpers no)
		(fp_line
			(start -0.508 -0.9398)
			(end -0.508 0.9398)
			(stroke
				(width 0.1524)
				(type default)
			)
			(layer "F.SilkS")
		)
		(fp_line
			(start 0.508 -0.9398)
			(end -0.508 -0.9398)
			(stroke
				(width 0.1524)
				(type default)
			)
			(layer "F.SilkS")
		)
		(fp_rect
			(start -0.508 0.9398)
			(end 0.508 -0.9398)
			(stroke
				(width 0)
				(type default)
			)
			(fill no)
			(layer "F.CrtYd")
		)
		(fp_rect
			(start -0.508 0.9398)
			(end 0.508 -0.9398)
			(stroke
				(width 0)
				(type default)
			)
			(fill no)
			(layer "F.Fab")
		)
		(pad "1" smd custom
			(at 0 -0.4445 270)
			(size 0.1397 0.1397)
			(layers "F.Cu" "F.Mask" "F.Paste")
			(net "SLOTID_0")
			(options
				(clearance outline)
				(anchor circle)
			)
			(primitives
				(gr_poly
					(pts
						(arc
							(start -0.1778 -0.2794)
							(mid -0.249642 -0.249642)
							(end -0.2794 -0.1778)
						)
						(arc
							(start -0.2794 0.1778)
							(mid -0.249642 0.249642)
							(end -0.1778 0.2794)
						)
						(arc
							(start 0.1778 0.2794)
							(mid 0.249642 0.249642)
							(end 0.2794 0.1778)
						)
						(arc
							(start 0.2794 -0.1778)
							(mid 0.249642 -0.249642)
							(end 0.1778 -0.2794)
						)
					)
					(width 0)
					(fill yes)
				)
			)
		)
		(pad "2" smd custom
			(at 0 0.4445 270)
			(size 0.1397 0.1397)
			(layers "F.Cu" "F.Mask" "F.Paste")
			(net "GND")
			(options
				(clearance outline)
				(anchor circle)
			)
			(primitives
				(gr_poly
					(pts
						(arc
							(start -0.1778 -0.2794)
							(mid -0.249642 -0.249642)
							(end -0.2794 -0.1778)
						)
						(arc
							(start -0.2794 0.1778)
							(mid -0.249642 0.249642)
							(end -0.1778 0.2794)
						)
						(arc
							(start 0.1778 0.2794)
							(mid 0.249642 0.249642)
							(end 0.2794 0.1778)
						)
						(arc
							(start 0.2794 -0.1778)
							(mid 0.249642 -0.249642)
							(end 0.1778 -0.2794)
						)
					)
					(width 0)
					(fill yes)
				)
			)
		)
	)
	(footprint ""
		(layer "F.Cu")
		(at 31.2674 -162.7378 180)
		(property "Reference" "C103"
			(at 0 0 180)
			(layer "F.SilkS")
			(hide yes)
			(effects
				(font
					(size 1.27 1.27)
				)
			)
		)
		(property "Value" "SCD1U16V2KX-3GP"
			(at 1.1811 -2.7051 180)
			(unlocked yes)
			(layer "F.Fab")
			(hide yes)
			(effects
				(font
					(size 1.016 1.016)
					(thickness 0.1524)
				)
			)
		)
		(property "Device Type" "C402H22"
			(at 1.1811 -4.2291 180)
			(unlocked yes)
			(layer "F.Fab")
			(hide yes)
			(effects
				(font
					(size 1.016 1.016)
					(thickness 0.1524)
				)
			)
		)
		(duplicate_pad_numbers_are_jumpers no)
		(fp_rect
			(start -0.4318 0.9525)
			(end 0.4318 -0.9525)
			(stroke
				(width 0)
				(type default)
			)
			(fill no)
			(layer "F.CrtYd")
		)
		(fp_rect
			(start -0.4318 0.9525)
			(end 0.4318 -0.9525)
			(stroke
				(width 0)
				(type default)
			)
			(fill no)
			(layer "F.Fab")
		)
		(pad "1" smd custom
			(at 0 -0.4445 180)
			(size 0.1524 0.1524)
			(layers "F.Cu" "F.Mask" "F.Paste")
			(net "V1PLLAV11")
			(options
				(clearance outline)
				(anchor circle)
			)
			(primitives
				(gr_poly
					(pts
						(arc
							(start 0.3048 -0.2032)
							(mid 0.275042 -0.275042)
							(end 0.2032 -0.3048)
						)
						(arc
							(start -0.2032 -0.3048)
							(mid -0.275042 -0.275042)
							(end -0.3048 -0.2032)
						)
						(arc
							(start -0.3048 0.2032)
							(mid -0.275042 0.275042)
							(end -0.2032 0.3048)
						)
						(arc
							(start 0.2032 0.3048)
							(mid 0.275042 0.275042)
							(end 0.3048 0.2032)
						)
					)
					(width 0)
					(fill yes)
				)
			)
		)
		(pad "2" smd custom
			(at 0 0.4445 180)
			(size 0.1524 0.1524)
			(layers "F.Cu" "F.Mask" "F.Paste")
			(net "GND")
			(options
				(clearance outline)
				(anchor circle)
			)
			(primitives
				(gr_poly
					(pts
						(arc
							(start 0.3048 -0.2032)
							(mid 0.275042 -0.275042)
							(end 0.2032 -0.3048)
						)
						(arc
							(start -0.2032 -0.3048)
							(mid -0.275042 -0.275042)
							(end -0.3048 -0.2032)
						)
						(arc
							(start -0.3048 0.2032)
							(mid -0.275042 0.275042)
							(end -0.2032 0.3048)
						)
						(arc
							(start 0.2032 0.3048)
							(mid 0.275042 0.275042)
							(end 0.3048 0.2032)
						)
					)
					(width 0)
					(fill yes)
				)
			)
		)
	)
	(footprint ""
		(layer "F.Cu")
		(at 98.414332 -18.402046 180)
		(property "Reference" "R46"
			(at 0 0 180)
			(layer "F.SilkS")
			(hide yes)
			(effects
				(font
					(size 1.27 1.27)
				)
			)
		)
		(property "Value" "0R2J-2-GP"
			(at 0.064008 -3.993896 180)
			(unlocked yes)
			(layer "F.Fab")
			(hide yes)
			(effects
				(font
					(size 1.016 1.016)
					(thickness 0.1524)
				)
			)
		)
		(property "Device Type" "R402H16"
			(at 0.064008 -5.517896 180)
			(unlocked yes)
			(layer "F.Fab")
			(hide yes)
			(effects
				(font
					(size 1.016 1.016)
					(thickness 0.1524)
				)
			)
		)
		(duplicate_pad_numbers_are_jumpers no)
		(fp_line
			(start 0.508 -0.9398)
			(end -0.508 -0.9398)
			(stroke
				(width 0.1524)
				(type default)
			)
			(layer "F.SilkS")
		)
		(fp_line
			(start -0.508 -0.9398)
			(end -0.508 0.9398)
			(stroke
				(width 0.1524)
				(type default)
			)
			(layer "F.SilkS")
		)
		(fp_rect
			(start -0.508 0.9398)
			(end 0.508 -0.9398)
			(stroke
				(width 0)
				(type default)
			)
			(fill no)
			(layer "F.CrtYd")
		)
		(fp_rect
			(start -0.508 0.9398)
			(end 0.508 -0.9398)
			(stroke
				(width 0)
				(type default)
			)
			(fill no)
			(layer "F.Fab")
		)
		(pad "1" smd custom
			(at 0 -0.4445 180)
			(size 0.1397 0.1397)
			(layers "F.Cu" "F.Mask" "F.Paste")
			(net "USB_P1_F_DN1")
			(options
				(clearance outline)
				(anchor circle)
			)
			(primitives
				(gr_poly
					(pts
						(arc
							(start -0.1778 -0.2794)
							(mid -0.249642 -0.249642)
							(end -0.2794 -0.1778)
						)
						(arc
							(start -0.2794 0.1778)
							(mid -0.249642 0.249642)
							(end -0.1778 0.2794)
						)
						(arc
							(start 0.1778 0.2794)
							(mid 0.249642 0.249642)
							(end 0.2794 0.1778)
						)
						(arc
							(start 0.2794 -0.1778)
							(mid 0.249642 -0.249642)
							(end 0.1778 -0.2794)
						)
					)
					(width 0)
					(fill yes)
				)
			)
		)
		(pad "2" smd custom
			(at 0 0.4445 180)
			(size 0.1397 0.1397)
			(layers "F.Cu" "F.Mask" "F.Paste")
			(net "USB_P1_DN")
			(options
				(clearance outline)
				(anchor circle)
			)
			(primitives
				(gr_poly
					(pts
						(arc
							(start -0.1778 -0.2794)
							(mid -0.249642 -0.249642)
							(end -0.2794 -0.1778)
						)
						(arc
							(start -0.2794 0.1778)
							(mid -0.249642 0.249642)
							(end -0.1778 0.2794)
						)
						(arc
							(start 0.1778 0.2794)
							(mid 0.249642 0.249642)
							(end 0.2794 0.1778)
						)
						(arc
							(start 0.2794 -0.1778)
							(mid 0.249642 -0.249642)
							(end 0.1778 -0.2794)
						)
					)
					(width 0)
					(fill yes)
				)
			)
		)
	)
	(footprint ""
		(layer "F.Cu")
		(at 216.261188 -36.833556 -90)
		(property "Reference" "C160"
			(at 0 0 270)
			(layer "F.SilkS")
			(hide yes)
			(effects
				(font
					(size 1.27 1.27)
				)
			)
		)
		(property "Value" "SCD1U50V3KX-GP"
			(at 0 -2.8194 270)
			(unlocked yes)
			(layer "F.Fab")
			(hide yes)
			(effects
				(font
					(size 1.016 1.016)
					(thickness 0.1524)
				)
			)
		)
		(property "Device Type" "C603H36"
			(at 0 -4.3434 270)
			(unlocked yes)
			(layer "F.Fab")
			(hide yes)
			(effects
				(font
					(size 1.016 1.016)
					(thickness 0.1524)
				)
			)
		)
		(duplicate_pad_numbers_are_jumpers no)
		(fp_line
			(start 0.508 0)
			(end -0.508 0)
			(stroke
				(width 0.2032)
				(type default)
			)
			(layer "F.SilkS")
		)
		(fp_rect
			(start -0.5842 1.3335)
			(end 0.5842 -1.3335)
			(stroke
				(width 0)
				(type default)
			)
			(fill no)
			(layer "F.CrtYd")
		)
		(fp_rect
			(start -0.5842 1.3335)
			(end 0.5842 -1.3335)
			(stroke
				(width 0)
				(type default)
			)
			(fill no)
			(layer "F.Fab")
		)
		(pad "1" smd custom
			(at 0 -0.762 270)
			(size 0.2159 0.2159)
			(layers "F.Cu" "F.Mask" "F.Paste")
			(net "P5V_STBY")
			(options
				(clearance outline)
				(anchor circle)
			)
			(primitives
				(gr_poly
					(pts
						(arc
							(start -0.3302 -0.4318)
							(mid -0.402042 -0.402042)
							(end -0.4318 -0.3302)
						)
						(arc
							(start -0.4318 0.3302)
							(mid -0.402042 0.402042)
							(end -0.3302 0.4318)
						)
						(arc
							(start 0.3302 0.4318)
							(mid 0.402042 0.402042)
							(end 0.4318 0.3302)
						)
						(arc
							(start 0.4318 -0.3302)
							(mid 0.402042 -0.402042)
							(end 0.3302 -0.4318)
						)
					)
					(width 0)
					(fill yes)
				)
			)
		)
		(pad "2" smd custom
			(at 0 0.762 270)
			(size 0.2159 0.2159)
			(layers "F.Cu" "F.Mask" "F.Paste")
			(net "P5V_LL_R")
			(options
				(clearance outline)
				(anchor circle)
			)
			(primitives
				(gr_poly
					(pts
						(arc
							(start -0.3302 -0.4318)
							(mid -0.402042 -0.402042)
							(end -0.4318 -0.3302)
						)
						(arc
							(start -0.4318 0.3302)
							(mid -0.402042 0.402042)
							(end -0.3302 0.4318)
						)
						(arc
							(start 0.3302 0.4318)
							(mid 0.402042 0.402042)
							(end 0.4318 0.3302)
						)
						(arc
							(start 0.4318 -0.3302)
							(mid 0.402042 -0.402042)
							(end 0.3302 -0.4318)
						)
					)
					(width 0)
					(fill yes)
				)
			)
		)
	)
	(footprint ""
		(layer "F.Cu")
		(at 69.52488 -182.73268 90)
		(property "Reference" "R509"
			(at 0 0 90)
			(layer "F.SilkS")
			(hide yes)
			(effects
				(font
					(size 1.27 1.27)
				)
			)
		)
		(property "Value" "4K75R2F-1-GP"
			(at 0.064008 -3.993896 90)
			(unlocked yes)
			(layer "F.Fab")
			(hide yes)
			(effects
				(font
					(size 1.016 1.016)
					(thickness 0.1524)
				)
			)
		)
		(property "Device Type" "R402H16"
			(at 0.064008 -5.517896 90)
			(unlocked yes)
			(layer "F.Fab")
			(hide yes)
			(effects
				(font
					(size 1.016 1.016)
					(thickness 0.1524)
				)
			)
		)
		(duplicate_pad_numbers_are_jumpers no)
		(fp_line
			(start 0.508 -0.9398)
			(end -0.508 -0.9398)
			(stroke
				(width 0.1524)
				(type default)
			)
			(layer "F.SilkS")
		)
		(fp_line
			(start -0.508 -0.9398)
			(end -0.508 0.9398)
			(stroke
				(width 0.1524)
				(type default)
			)
			(layer "F.SilkS")
		)
		(fp_rect
			(start -0.508 0.9398)
			(end 0.508 -0.9398)
			(stroke
				(width 0)
				(type default)
			)
			(fill no)
			(layer "F.CrtYd")
		)
		(fp_rect
			(start -0.508 0.9398)
			(end 0.508 -0.9398)
			(stroke
				(width 0)
				(type default)
			)
			(fill no)
			(layer "F.Fab")
		)
		(pad "1" smd custom
			(at 0 -0.4445 90)
			(size 0.1397 0.1397)
			(layers "F.Cu" "F.Mask" "F.Paste")
			(net "P3V3_STBY")
			(options
				(clearance outline)
				(anchor circle)
			)
			(primitives
				(gr_poly
					(pts
						(arc
							(start -0.1778 -0.2794)
							(mid -0.249642 -0.249642)
							(end -0.2794 -0.1778)
						)
						(arc
							(start -0.2794 0.1778)
							(mid -0.249642 0.249642)
							(end -0.1778 0.2794)
						)
						(arc
							(start 0.1778 0.2794)
							(mid 0.249642 0.249642)
							(end 0.2794 0.1778)
						)
						(arc
							(start 0.2794 -0.1778)
							(mid 0.249642 -0.249642)
							(end 0.1778 -0.2794)
						)
					)
					(width 0)
					(fill yes)
				)
			)
		)
		(pad "2" smd custom
			(at 0 0.4445 90)
			(size 0.1397 0.1397)
			(layers "F.Cu" "F.Mask" "F.Paste")
			(net "TPS74801_P2V5_STBY_EN")
			(options
				(clearance outline)
				(anchor circle)
			)
			(primitives
				(gr_poly
					(pts
						(arc
							(start -0.1778 -0.2794)
							(mid -0.249642 -0.249642)
							(end -0.2794 -0.1778)
						)
						(arc
							(start -0.2794 0.1778)
							(mid -0.249642 0.249642)
							(end -0.1778 0.2794)
						)
						(arc
							(start 0.1778 0.2794)
							(mid 0.249642 0.249642)
							(end 0.2794 0.1778)
						)
						(arc
							(start 0.2794 -0.1778)
							(mid 0.249642 -0.249642)
							(end 0.1778 -0.2794)
						)
					)
					(width 0)
					(fill yes)
				)
			)
		)
	)
	(footprint ""
		(layer "F.Cu")
		(at 134.873492 -18.143474)
		(property "Reference" "D1"
			(at 0 0 0)
			(layer "F.SilkS")
			(hide yes)
			(effects
				(font
					(size 1.27 1.27)
				)
			)
		)
		(property "Value" "SMF15A-GP"
			(at -2.0955 1.2192 0)
			(unlocked yes)
			(layer "F.Fab")
			(hide yes)
			(effects
				(font
					(size 1.016 1.016)
					(thickness 0.1524)
				)
			)
		)
		(property "Device Type" "SOD123AK-2H43"
			(at -2.0955 -0.3048 0)
			(unlocked yes)
			(layer "F.Fab")
			(hide yes)
			(effects
				(font
					(size 1.016 1.016)
					(thickness 0.1524)
				)
			)
		)
		(duplicate_pad_numbers_are_jumpers no)
		(fp_line
			(start -1.1557 -2.7686)
			(end -1.1557 2.7686)
			(stroke
				(width 0.1524)
				(type default)
			)
			(layer "F.SilkS")
		)
		(fp_line
			(start -1.1557 2.7686)
			(end 1.1557 2.7686)
			(stroke
				(width 0.1524)
				(type default)
			)
			(layer "F.SilkS")
		)
		(fp_line
			(start 1.1557 -2.7686)
			(end -1.1557 -2.7686)
			(stroke
				(width 0.1524)
				(type default)
			)
			(layer "F.SilkS")
		)
		(fp_line
			(start 1.1557 2.7686)
			(end 1.1557 -2.7686)
			(stroke
				(width 0.1524)
				(type default)
			)
			(layer "F.SilkS")
		)
		(fp_line
			(start 1.1557 2.921)
			(end -1.1557 2.921)
			(stroke
				(width 0.508)
				(type default)
			)
			(layer "F.SilkS")
		)
		(fp_poly
			(pts
				(xy -0.4572 1.8669) (xy -0.4572 1.397) (xy -0.9017 1.397) (xy -0.9017 -1.397) (xy -0.4572 -1.397)
				(xy -0.4572 -1.8669) (xy 0.4572 -1.8669) (xy 0.4572 -1.397) (xy 0.9017 -1.397) (xy 0.9017 1.397)
				(xy 0.4572 1.397) (xy 0.4572 1.8669)
			)
			(stroke
				(width 0)
				(type default)
			)
			(fill no)
			(layer "F.CrtYd")
		)
		(fp_poly
			(pts
				(xy -1.4097 2.8448) (xy -1.4097 -2.8448) (xy 1.4097 -2.8448) (xy 1.4097 1.3716) (xy 0.9017 1.3716)
				(xy 0.9017 -1.397) (xy 0.4572 -1.397) (xy 0.4572 -1.8669) (xy -0.4572 -1.8669) (xy -0.4572 -1.397)
				(xy -0.9017 -1.397) (xy -0.9017 1.397) (xy -0.4572 1.397) (xy -0.4572 1.8669) (xy 0.4572 1.8669)
				(xy 0.4572 1.397) (xy 0.9017 1.397) (xy 0.9017 1.3843) (xy 1.4097 1.3843) (xy 1.4097 2.8448)
			)
			(stroke
				(width 0)
				(type default)
			)
			(fill no)
			(layer "F.CrtYd")
		)
		(fp_rect
			(start -1.4097 2.8448)
			(end 1.4097 -2.8448)
			(stroke
				(width 0)
				(type default)
			)
			(fill no)
			(layer "F.Fab")
		)
		(pad "A" smd rect
			(at 0 -1.75768)
			(size 1.143 1.4986)
			(layers "F.Cu" "F.Mask" "F.Paste")
			(net "GND")
		)
		(pad "K" smd rect
			(at 0 1.75768)
			(size 1.143 1.4986)
			(layers "F.Cu" "F.Mask" "F.Paste")
			(net "P12V_IOM")
		)
	)
	(footprint ""
		(layer "F.Cu")
		(at 10.771124 -135.285988 90)
		(property "Reference" "R224"
			(at 0 0 90)
			(layer "F.SilkS")
			(hide yes)
			(effects
				(font
					(size 1.27 1.27)
				)
			)
		)
		(property "Value" "4K7R2F-GP"
			(at 0.064008 -3.993896 90)
			(unlocked yes)
			(layer "F.Fab")
			(hide yes)
			(effects
				(font
					(size 1.016 1.016)
					(thickness 0.1524)
				)
			)
		)
		(property "Device Type" "R402H16"
			(at 0.064008 -5.517896 90)
			(unlocked yes)
			(layer "F.Fab")
			(hide yes)
			(effects
				(font
					(size 1.016 1.016)
					(thickness 0.1524)
				)
			)
		)
		(duplicate_pad_numbers_are_jumpers no)
		(fp_line
			(start 0.508 -0.9398)
			(end -0.508 -0.9398)
			(stroke
				(width 0.1524)
				(type default)
			)
			(layer "F.SilkS")
		)
		(fp_line
			(start -0.508 -0.9398)
			(end -0.508 0.9398)
			(stroke
				(width 0.1524)
				(type default)
			)
			(layer "F.SilkS")
		)
		(fp_rect
			(start -0.508 0.9398)
			(end 0.508 -0.9398)
			(stroke
				(width 0)
				(type default)
			)
			(fill no)
			(layer "F.CrtYd")
		)
		(fp_rect
			(start -0.508 0.9398)
			(end 0.508 -0.9398)
			(stroke
				(width 0)
				(type default)
			)
			(fill no)
			(layer "F.Fab")
		)
		(pad "1" smd custom
			(at 0 -0.4445 90)
			(size 0.1397 0.1397)
			(layers "F.Cu" "F.Mask" "F.Paste")
			(net "MEM_PAR")
			(options
				(clearance outline)
				(anchor circle)
			)
			(primitives
				(gr_poly
					(pts
						(arc
							(start -0.1778 -0.2794)
							(mid -0.249642 -0.249642)
							(end -0.2794 -0.1778)
						)
						(arc
							(start -0.2794 0.1778)
							(mid -0.249642 0.249642)
							(end -0.1778 0.2794)
						)
						(arc
							(start 0.1778 0.2794)
							(mid 0.249642 0.249642)
							(end 0.2794 0.1778)
						)
						(arc
							(start 0.2794 -0.1778)
							(mid 0.249642 -0.249642)
							(end 0.1778 -0.2794)
						)
					)
					(width 0)
					(fill yes)
				)
			)
		)
		(pad "2" smd custom
			(at 0 0.4445 90)
			(size 0.1397 0.1397)
			(layers "F.Cu" "F.Mask" "F.Paste")
			(net "P1V2_STBY")
			(options
				(clearance outline)
				(anchor circle)
			)
			(primitives
				(gr_poly
					(pts
						(arc
							(start -0.1778 -0.2794)
							(mid -0.249642 -0.249642)
							(end -0.2794 -0.1778)
						)
						(arc
							(start -0.2794 0.1778)
							(mid -0.249642 0.249642)
							(end -0.1778 0.2794)
						)
						(arc
							(start 0.1778 0.2794)
							(mid 0.249642 0.249642)
							(end 0.2794 0.1778)
						)
						(arc
							(start 0.2794 -0.1778)
							(mid 0.249642 -0.249642)
							(end 0.1778 -0.2794)
						)
					)
					(width 0)
					(fill yes)
				)
			)
		)
	)
)
